# BASEBOARD_FAB2 (Tioga Pass) — schematic netlist excerpt (pin names and nets, part order shuffled) for the footprints in the layout excerpt that follows; sources: Cadence DE-HDL packaged netlist, KiCad conversion of Wiwynn_Tioga_Pass_MB.brd

R4D63  RES  22.1 1.0% CHIP  pkg 0402  page 201 : A = VR_VRRDY_PVCCIN_CPU0 ; B = PWRGD_PVCCIN_CPU0
R1G1  RES  2 1.0% CHIP  pkg 0402  page 100 : A = M_H_CPU_VREF ; B = M_H_VREF
C5D59  CAP_A  22.0UF 4V 20% X6S  pkg 0603V  page 217 : A = PVDDQ_ABC ; B = GND

(kicad_pcb
	(version 20260206)
	(generator "pcbnew")
	(generator_version "10.0")
	(general
		(thickness 1.6)
		(legacy_teardrops no)
	)
	(paper "A4")
	(title_block
		(title "Wiwynn_Tioga_Pass_MB.brd")
		(comment 1 "Tioga Pass / footprints 2015-2017 of 4770")
	)
	(layers
		(0 "F.Cu" signal "TOP")
		(4 "In1.Cu" signal "L2GND")
		(6 "In2.Cu" signal "L3")
		(8 "In3.Cu" signal "L4GND")
		(10 "In4.Cu" signal "L5")
		(12 "In5.Cu" signal "L6GND")
		(14 "In6.Cu" signal "L7VCC")
		(16 "In7.Cu" signal "L8VCC")
		(18 "In8.Cu" signal "L9GND")
		(20 "In9.Cu" signal "L10")
		(22 "In10.Cu" signal "L11GND")
		(24 "In11.Cu" signal "L12")
		(26 "In12.Cu" signal "L13GND")
		(2 "B.Cu" signal "BOTTOM")
		(9 "F.Adhes" user "F.Adhesive")
		(11 "B.Adhes" user "B.Adhesive")
		(13 "F.Paste" user "Package Geometry/Pastemask Top")
		(15 "B.Paste" user "Package Geometry/Pastemask Bottom")
		(5 "F.SilkS" user "Ref Des/Silkscreen Top")
		(7 "B.SilkS" user "Ref Des/Silkscreen Bottom")
		(1 "F.Mask" user "Board Geometry/Soldermask Top")
		(3 "B.Mask" user "Board Geometry/Soldermask Bottom")
		(17 "Dwgs.User" user "User.Drawings")
		(19 "Cmts.User" user "User.Comments")
		(21 "Eco1.User" user "User.Eco1")
		(23 "Eco2.User" user "User.Eco2")
		(25 "Edge.Cuts" user "Board Geometry/Outline")
		(27 "Margin" user)
		(31 "F.CrtYd" user "Package Geometry/Place Bound Top")
		(29 "B.CrtYd" user "Package Geometry/Place Bound Bottom")
		(35 "F.Fab" user "Ref Des/Assembly Top")
		(33 "B.Fab" user "Ref Des/Assembly Bottom")
	)
	(footprint ""
		(layer "F.Cu")
		(at 27.785568 -13.3985)
		(property "Reference" "R1G1"
			(at 0 0 0)
			(layer "F.SilkS")
			(hide yes)
			(effects
				(font
					(size 1.27 1.27)
				)
			)
		)
		(property "Value" ""
			(at 0 0 0)
			(layer "F.Fab")
			(effects
				(font
					(size 1.27 1.27)
				)
			)
		)
		(duplicate_pad_numbers_are_jumpers no)
		(fp_poly
			(pts
				(xy -0.2794 -0.1016) (xy 0.2794 -0.1016) (xy 0.2794 0.9906) (xy -0.2794 0.9906)
			)
			(stroke
				(width 0)
				(type default)
			)
			(fill no)
			(layer "F.CrtYd")
		)
		(fp_line
			(start -0.2794 -0.1016)
			(end -0.2794 0.9906)
			(stroke
				(width 0.1)
				(type default)
			)
			(layer "F.Fab")
		)
		(fp_line
			(start -0.2794 0.9906)
			(end 0.2794 0.9906)
			(stroke
				(width 0.1)
				(type default)
			)
			(layer "F.Fab")
		)
		(fp_line
			(start 0.2794 -0.1016)
			(end -0.2794 -0.1016)
			(stroke
				(width 0.1)
				(type default)
			)
			(layer "F.Fab")
		)
		(fp_line
			(start 0.2794 0.9906)
			(end 0.2794 -0.1016)
			(stroke
				(width 0.1)
				(type default)
			)
			(layer "F.Fab")
		)
		(pad "1" smd rect
			(at 0 0)
			(size 0.508 0.508)
			(layers "F.Cu" "F.Mask" "F.Paste")
			(net "M_H_CPU_VREF")
		)
		(pad "2" smd rect
			(at 0 0.889)
			(size 0.508 0.508)
			(layers "F.Cu" "F.Mask" "F.Paste")
			(net "M_H_VREF")
		)
		(zone
			(layer "F.Cu")
			(hatch none 0.5)
			(connect_pads
				(clearance 0)
			)
			(min_thickness 0.25)
			(keepout
				(tracks allowed)
				(vias not_allowed)
				(pads allowed)
				(copperpour not_allowed)
				(footprints allowed)
			)
			(placement
				(enabled no)
				(sheetname "")
			)
			(fill
				(thermal_gap 0.5)
				(thermal_bridge_width 0.5)
				(island_removal_mode 0)
			)
			(polygon
				(pts
					(xy 27.531568 -13.1445) (xy 28.039568 -13.1445) (xy 28.039568 -12.7635) (xy 27.531568 -12.7635)
				)
			)
		)
		(zone
			(layer "F.Cu")
			(hatch none 0.5)
			(connect_pads
				(clearance 0)
			)
			(min_thickness 0.25)
			(keepout
				(tracks not_allowed)
				(vias allowed)
				(pads allowed)
				(copperpour not_allowed)
				(footprints allowed)
			)
			(placement
				(enabled no)
				(sheetname "")
			)
			(fill
				(thermal_gap 0.5)
				(thermal_bridge_width 0.5)
				(island_removal_mode 0)
			)
			(polygon
				(pts
					(xy 27.531568 -12.7635) (xy 28.039568 -12.7635) (xy 28.039568 -13.1445) (xy 27.531568 -13.1445)
				)
			)
		)
	)
	(footprint ""
		(layer "F.Cu")
		(at 269.645638 -68.365116 180)
		(property "Reference" "C5D59"
			(at 0 0 180)
			(layer "F.SilkS")
			(hide yes)
			(effects
				(font
					(size 1.27 1.27)
				)
			)
		)
		(property "Value" ""
			(at 0 0 180)
			(layer "F.Fab")
			(effects
				(font
					(size 1.27 1.27)
				)
			)
		)
		(duplicate_pad_numbers_are_jumpers no)
		(fp_poly
			(pts
				(xy -0.4953 -0.2032) (xy 0.4953 -0.2032) (xy 0.4953 1.6002) (xy -0.4953 1.6002)
			)
			(stroke
				(width 0)
				(type default)
			)
			(fill no)
			(layer "F.CrtYd")
		)
		(fp_line
			(start 0.4953 1.6002)
			(end -0.4953 1.6002)
			(stroke
				(width 0.1)
				(type default)
			)
			(layer "F.Fab")
		)
		(fp_line
			(start 0.4953 -0.2032)
			(end 0.4953 1.6002)
			(stroke
				(width 0.1)
				(type default)
			)
			(layer "F.Fab")
		)
		(fp_line
			(start -0.4953 1.6002)
			(end -0.4953 -0.2032)
			(stroke
				(width 0.1)
				(type default)
			)
			(layer "F.Fab")
		)
		(fp_line
			(start -0.4953 -0.2032)
			(end 0.4953 -0.2032)
			(stroke
				(width 0.1)
				(type default)
			)
			(layer "F.Fab")
		)
		(pad "1" smd rect
			(at 0 0 180)
			(size 0.762 0.889)
			(layers "F.Cu" "F.Mask" "F.Paste")
			(net "PVDDQ_ABC")
		)
		(pad "2" smd rect
			(at 0 1.397 180)
			(size 0.762 0.889)
			(layers "F.Cu" "F.Mask" "F.Paste")
			(net "GND")
		)
		(zone
			(layer "F.Cu")
			(hatch none 0.5)
			(connect_pads
				(clearance 0)
			)
			(min_thickness 0.25)
			(keepout
				(tracks not_allowed)
				(vias allowed)
				(pads allowed)
				(copperpour not_allowed)
				(footprints allowed)
			)
			(placement
				(enabled no)
				(sheetname "")
			)
			(fill
				(thermal_gap 0.5)
				(thermal_bridge_width 0.5)
				(island_removal_mode 0)
			)
			(polygon
				(pts
					(xy 270.026638 -68.809616) (xy 269.264638 -68.809616) (xy 269.264638 -69.317616) (xy 270.026638 -69.317616)
				)
			)
		)
	)
	(footprint ""
		(layer "F.Cu")
		(at 179.6288 -65.7606 -90)
		(property "Reference" "R4D63"
			(at 0 0 270)
			(layer "F.SilkS")
			(hide yes)
			(effects
				(font
					(size 1.27 1.27)
				)
			)
		)
		(property "Value" ""
			(at 0 0 270)
			(layer "F.Fab")
			(effects
				(font
					(size 1.27 1.27)
				)
			)
		)
		(duplicate_pad_numbers_are_jumpers no)
		(fp_poly
			(pts
				(xy -0.2794 -0.1016) (xy 0.2794 -0.1016) (xy 0.2794 0.9906) (xy -0.2794 0.9906)
			)
			(stroke
				(width 0)
				(type default)
			)
			(fill no)
			(layer "F.CrtYd")
		)
		(fp_line
			(start -0.2794 0.9906)
			(end 0.2794 0.9906)
			(stroke
				(width 0.1)
				(type default)
			)
			(layer "F.Fab")
		)
		(fp_line
			(start 0.2794 0.9906)
			(end 0.2794 -0.1016)
			(stroke
				(width 0.1)
				(type default)
			)
			(layer "F.Fab")
		)
		(fp_line
			(start -0.2794 -0.1016)
			(end -0.2794 0.9906)
			(stroke
				(width 0.1)
				(type default)
			)
			(layer "F.Fab")
		)
		(fp_line
			(start 0.2794 -0.1016)
			(end -0.2794 -0.1016)
			(stroke
				(width 0.1)
				(type default)
			)
			(layer "F.Fab")
		)
		(pad "1" smd rect
			(at 0 0 270)
			(size 0.508 0.508)
			(layers "F.Cu" "F.Mask" "F.Paste")
			(net "VR_VRRDY_PVCCIN_CPU0")
		)
		(pad "2" smd rect
			(at 0 0.889 270)
			(size 0.508 0.508)
			(layers "F.Cu" "F.Mask" "F.Paste")
			(net "PWRGD_PVCCIN_CPU0")
		)
		(zone
			(layer "F.Cu")
			(hatch none 0.5)
			(connect_pads
				(clearance 0)
			)
			(min_thickness 0.25)
			(keepout
				(tracks not_allowed)
				(vias allowed)
				(pads allowed)
				(copperpour not_allowed)
				(footprints allowed)
			)
			(placement
				(enabled no)
				(sheetname "")
			)
			(fill
				(thermal_gap 0.5)
				(thermal_bridge_width 0.5)
				(island_removal_mode 0)
			)
			(polygon
				(pts
					(xy 178.9938 -66.0146) (xy 178.9938 -65.5066) (xy 179.3748 -65.5066) (xy 179.3748 -66.0146)
				)
			)
		)
		(zone
			(layer "F.Cu")
			(hatch none 0.5)
			(connect_pads
				(clearance 0)
			)
			(min_thickness 0.25)
			(keepout
				(tracks allowed)
				(vias not_allowed)
				(pads allowed)
				(copperpour not_allowed)
				(footprints allowed)
			)
			(placement
				(enabled no)
				(sheetname "")
			)
			(fill
				(thermal_gap 0.5)
				(thermal_bridge_width 0.5)
				(island_removal_mode 0)
			)
			(polygon
				(pts
					(xy 179.3748 -66.0146) (xy 179.3748 -65.5066) (xy 178.9938 -65.5066) (xy 178.9938 -66.0146)
				)
			)
		)
	)
)
